(kicad_pcb
	(version 20260206)
	(generator "pcbnew")
	(generator_version "10.0")
	(general
		(thickness 1.6)
		(legacy_teardrops no)
	)
	(paper "A4")
	(title_block
		(title "Wiwynn_Tioga_Pass_MB.brd")
		(comment 1 "Tioga Pass / footprints 2358-2365 of 4770")
	)
	(layers
		(0 "F.Cu" signal "TOP")
		(4 "In1.Cu" signal "L2GND")
		(6 "In2.Cu" signal "L3")
		(8 "In3.Cu" signal "L4GND")
		(10 "In4.Cu" signal "L5")
		(12 "In5.Cu" signal "L6GND")
		(14 "In6.Cu" signal "L7VCC")
		(16 "In7.Cu" signal "L8VCC")
		(18 "In8.Cu" signal "L9GND")
		(20 "In9.Cu" signal "L10")
		(22 "In10.Cu" signal "L11GND")
		(24 "In11.Cu" signal "L12")
		(26 "In12.Cu" signal "L13GND")
		(2 "B.Cu" signal "BOTTOM")
		(9 "F.Adhes" user "F.Adhesive")
		(11 "B.Adhes" user "B.Adhesive")
		(13 "F.Paste" user "Package Geometry/Pastemask Top")
		(15 "B.Paste" user "Package Geometry/Pastemask Bottom")
		(5 "F.SilkS" user "Ref Des/Silkscreen Top")
		(7 "B.SilkS" user "Ref Des/Silkscreen Bottom")
		(1 "F.Mask" user "Board Geometry/Soldermask Top")
		(3 "B.Mask" user "Board Geometry/Soldermask Bottom")
		(17 "Dwgs.User" user "User.Drawings")
		(19 "Cmts.User" user "User.Comments")
		(21 "Eco1.User" user "User.Eco1")
		(23 "Eco2.User" user "User.Eco2")
		(25 "Edge.Cuts" user "Board Geometry/Outline")
		(27 "Margin" user)
		(31 "F.CrtYd" user "Package Geometry/Place Bound Top")
		(29 "B.CrtYd" user "Package Geometry/Place Bound Bottom")
		(35 "F.Fab" user "Ref Des/Assembly Top")
		(33 "B.Fab" user "Ref Des/Assembly Bottom")
	)
	(footprint ""
		(layer "B.Cu")
		(at 182.736998 -5.321808)
		(property "Reference" "R6U5"
			(at 0 0 0)
			(layer "B.SilkS")
			(hide yes)
			(effects
				(font
					(size 1.27 1.27)
				)
				(justify mirror)
			)
		)
		(property "Value" ""
			(at 0 0 0)
			(layer "B.Fab")
			(effects
				(font
					(size 1.27 1.27)
				)
				(justify mirror)
			)
		)
		(duplicate_pad_numbers_are_jumpers no)
		(fp_rect
			(start 0.2794 0.9906)
			(end -0.2794 -0.1016)
			(stroke
				(width 0)
				(type default)
			)
			(fill no)
			(layer "B.CrtYd")
		)
		(fp_line
			(start -0.2794 -0.1016)
			(end 0.2794 -0.1016)
			(stroke
				(width 0.1)
				(type default)
			)
			(layer "B.Fab")
		)
		(fp_line
			(start -0.2794 0.9906)
			(end -0.2794 -0.1016)
			(stroke
				(width 0.1)
				(type default)
			)
			(layer "B.Fab")
		)
		(fp_line
			(start 0.2794 -0.1016)
			(end 0.2794 0.9906)
			(stroke
				(width 0.1)
				(type default)
			)
			(layer "B.Fab")
		)
		(fp_line
			(start 0.2794 0.9906)
			(end -0.2794 0.9906)
			(stroke
				(width 0.1)
				(type default)
			)
			(layer "B.Fab")
		)
		(pad "1" smd rect
			(at 0 0 180)
			(size 0.508 0.508)
			(layers "B.Cu" "B.Mask" "B.Paste")
			(net "PVDDQ_ABC")
		)
		(pad "2" smd rect
			(at 0 0.889 180)
			(size 0.508 0.508)
			(layers "B.Cu" "B.Mask" "B.Paste")
			(net "VSENSE_PVDDQ_ABC_VTT")
		)
		(zone
			(layer "B.Cu")
			(hatch none 0.5)
			(connect_pads
				(clearance 0)
			)
			(min_thickness 0.25)
			(keepout
				(tracks allowed)
				(vias not_allowed)
				(pads allowed)
				(copperpour not_allowed)
				(footprints allowed)
			)
			(placement
				(enabled no)
				(sheetname "")
			)
			(fill
				(thermal_gap 0.5)
				(thermal_bridge_width 0.5)
				(island_removal_mode 0)
			)
			(polygon
				(pts
					(xy 182.990998 -4.686808) (xy 182.990998 -5.067808) (xy 182.482998 -5.067808) (xy 182.482998 -4.686808)
				)
			)
		)
	)
	(footprint ""
		(layer "B.Cu")
		(at 259.09778 -149.7711 90)
		(property "Reference" "C5G77"
			(at -1.64973 0.78994 180)
			(unlocked yes)
			(layer "B.SilkS")
			(effects
				(font
					(size 0.7874 0.5842)
					(thickness 0.1524)
				)
				(justify mirror)
			)
		)
		(property "Value" ""
			(at 0 0 90)
			(layer "B.Fab")
			(effects
				(font
					(size 1.27 1.27)
				)
				(justify mirror)
			)
		)
		(duplicate_pad_numbers_are_jumpers no)
		(fp_rect
			(start -0.7239 -0.2159)
			(end 0.7239 1.9939)
			(stroke
				(width 0)
				(type default)
			)
			(fill no)
			(layer "B.CrtYd")
		)
		(fp_line
			(start 0.7239 -0.2159)
			(end 0.7239 1.9939)
			(stroke
				(width 0.1)
				(type default)
			)
			(layer "B.Fab")
		)
		(fp_line
			(start -0.7239 -0.2159)
			(end 0.7239 -0.2159)
			(stroke
				(width 0.1)
				(type default)
			)
			(layer "B.Fab")
		)
		(fp_line
			(start 0.7239 1.9939)
			(end -0.7239 1.9939)
			(stroke
				(width 0.1)
				(type default)
			)
			(layer "B.Fab")
		)
		(fp_line
			(start -0.7239 1.9939)
			(end -0.7239 -0.2159)
			(stroke
				(width 0.1)
				(type default)
			)
			(layer "B.Fab")
		)
		(pad "1" smd rect
			(at 0 0 270)
			(size 1.27 1.016)
			(layers "B.Cu" "B.Mask" "B.Paste")
			(net "PVDDQ_DEF")
		)
		(pad "2" smd rect
			(at 0 1.778 270)
			(size 1.27 1.016)
			(layers "B.Cu" "B.Mask" "B.Paste")
			(net "GND")
		)
		(zone
			(layer "B.Cu")
			(hatch none 0.5)
			(connect_pads
				(clearance 0)
			)
			(min_thickness 0.25)
			(keepout
				(tracks not_allowed)
				(vias allowed)
				(pads allowed)
				(copperpour not_allowed)
				(footprints allowed)
			)
			(placement
				(enabled no)
				(sheetname "")
			)
			(fill
				(thermal_gap 0.5)
				(thermal_bridge_width 0.5)
				(island_removal_mode 0)
			)
			(polygon
				(pts
					(xy 259.60578 -149.1361) (xy 260.36778 -149.1361) (xy 260.36778 -150.4061) (xy 259.60578 -150.4061)
				)
			)
		)
	)
	(footprint ""
		(layer "B.Cu")
		(at 470.027 -56.388 -90)
		(property "Reference" "R1R22"
			(at 0 0 90)
			(layer "B.SilkS")
			(hide yes)
			(effects
				(font
					(size 1.27 1.27)
				)
				(justify mirror)
			)
		)
		(property "Value" ""
			(at 0 0 90)
			(layer "B.Fab")
			(effects
				(font
					(size 1.27 1.27)
				)
				(justify mirror)
			)
		)
		(duplicate_pad_numbers_are_jumpers no)
		(fp_poly
			(pts
				(xy 0.2794 -0.1016) (xy -0.2794 -0.1016) (xy -0.2794 0.9906) (xy 0.2794 0.9906)
			)
			(stroke
				(width 0)
				(type default)
			)
			(fill no)
			(layer "B.CrtYd")
		)
		(fp_line
			(start -0.2794 0.9906)
			(end -0.2794 -0.1016)
			(stroke
				(width 0.1)
				(type default)
			)
			(layer "B.Fab")
		)
		(fp_line
			(start 0.2794 0.9906)
			(end -0.2794 0.9906)
			(stroke
				(width 0.1)
				(type default)
			)
			(layer "B.Fab")
		)
		(fp_line
			(start -0.2794 -0.1016)
			(end 0.2794 -0.1016)
			(stroke
				(width 0.1)
				(type default)
			)
			(layer "B.Fab")
		)
		(fp_line
			(start 0.2794 -0.1016)
			(end 0.2794 0.9906)
			(stroke
				(width 0.1)
				(type default)
			)
			(layer "B.Fab")
		)
		(pad "1" smd rect
			(at 0 0 90)
			(size 0.508 0.508)
			(layers "B.Cu" "B.Mask" "B.Paste")
			(net "P3V3_STBY")
		)
		(pad "2" smd rect
			(at 0 0.889 90)
			(size 0.508 0.508)
			(layers "B.Cu" "B.Mask" "B.Paste")
			(net "SMB_PCH_MEZZ_LOM3_SDA")
		)
		(zone
			(layer "B.Cu")
			(hatch none 0.5)
			(connect_pads
				(clearance 0)
			)
			(min_thickness 0.25)
			(keepout
				(tracks not_allowed)
				(vias allowed)
				(pads allowed)
				(copperpour not_allowed)
				(footprints allowed)
			)
			(placement
				(enabled no)
				(sheetname "")
			)
			(fill
				(thermal_gap 0.5)
				(thermal_bridge_width 0.5)
				(island_removal_mode 0)
			)
			(polygon
				(pts
					(xy 469.392 -56.134) (xy 469.392 -56.642) (xy 469.773 -56.642) (xy 469.773 -56.134)
				)
			)
		)
		(zone
			(layer "B.Cu")
			(hatch none 0.5)
			(connect_pads
				(clearance 0)
			)
			(min_thickness 0.25)
			(keepout
				(tracks allowed)
				(vias not_allowed)
				(pads allowed)
				(copperpour not_allowed)
				(footprints allowed)
			)
			(placement
				(enabled no)
				(sheetname "")
			)
			(fill
				(thermal_gap 0.5)
				(thermal_bridge_width 0.5)
				(island_removal_mode 0)
			)
			(polygon
				(pts
					(xy 469.773 -56.134) (xy 469.773 -56.642) (xy 469.392 -56.642) (xy 469.392 -56.134)
				)
			)
		)
	)
	(footprint ""
		(layer "B.Cu")
		(at 443.1538 -142.0368 -90)
		(property "Reference" "R25W178"
			(at 0.8382 -0.67818 270)
			(unlocked yes)
			(layer "B.SilkS")
			(effects
				(font
					(size 0.4064 0.254)
					(thickness 0.1524)
				)
				(justify left mirror)
			)
		)
		(property "Value" ""
			(at 0 0 90)
			(layer "B.Fab")
			(effects
				(font
					(size 1.27 1.27)
				)
				(justify mirror)
			)
		)
		(duplicate_pad_numbers_are_jumpers no)
		(fp_poly
			(pts
				(xy 0.2794 -0.1016) (xy -0.2794 -0.1016) (xy -0.2794 0.9906) (xy 0.2794 0.9906)
			)
			(stroke
				(width 0)
				(type default)
			)
			(fill no)
			(layer "B.CrtYd")
		)
		(fp_line
			(start -0.2794 0.9906)
			(end -0.2794 -0.1016)
			(stroke
				(width 0.1)
				(type default)
			)
			(layer "B.Fab")
		)
		(fp_line
			(start 0.2794 0.9906)
			(end -0.2794 0.9906)
			(stroke
				(width 0.1)
				(type default)
			)
			(layer "B.Fab")
		)
		(fp_line
			(start -0.2794 -0.1016)
			(end 0.2794 -0.1016)
			(stroke
				(width 0.1)
				(type default)
			)
			(layer "B.Fab")
		)
		(fp_line
			(start 0.2794 -0.1016)
			(end 0.2794 0.9906)
			(stroke
				(width 0.1)
				(type default)
			)
			(layer "B.Fab")
		)
		(pad "1" smd rect
			(at 0 0 90)
			(size 0.508 0.508)
			(layers "B.Cu" "B.Mask" "B.Paste")
			(net "P3V3_STBY")
		)
		(pad "2" smd rect
			(at 0 0.889 90)
			(size 0.508 0.508)
			(layers "B.Cu" "B.Mask" "B.Paste")
			(net "BMC_PWR_DEBUG_BUF_N")
		)
		(zone
			(layer "B.Cu")
			(hatch none 0.5)
			(connect_pads
				(clearance 0)
			)
			(min_thickness 0.25)
			(keepout
				(tracks not_allowed)
				(vias allowed)
				(pads allowed)
				(copperpour not_allowed)
				(footprints allowed)
			)
			(placement
				(enabled no)
				(sheetname "")
			)
			(fill
				(thermal_gap 0.5)
				(thermal_bridge_width 0.5)
				(island_removal_mode 0)
			)
			(polygon
				(pts
					(xy 442.5188 -141.7828) (xy 442.5188 -142.2908) (xy 442.8998 -142.2908) (xy 442.8998 -141.7828)
				)
			)
		)
		(zone
			(layer "B.Cu")
			(hatch none 0.5)
			(connect_pads
				(clearance 0)
			)
			(min_thickness 0.25)
			(keepout
				(tracks allowed)
				(vias not_allowed)
				(pads allowed)
				(copperpour not_allowed)
				(footprints allowed)
			)
			(placement
				(enabled no)
				(sheetname "")
			)
			(fill
				(thermal_gap 0.5)
				(thermal_bridge_width 0.5)
				(island_removal_mode 0)
			)
			(polygon
				(pts
					(xy 442.8998 -141.7828) (xy 442.8998 -142.2908) (xy 442.5188 -142.2908) (xy 442.5188 -141.7828)
				)
			)
		)
	)
	(footprint ""
		(layer "B.Cu")
		(at 393.362688 -153.552144 90)
		(property "Reference" "R2L9"
			(at 0 0 90)
			(layer "B.SilkS")
			(hide yes)
			(effects
				(font
					(size 1.27 1.27)
				)
				(justify mirror)
			)
		)
		(property "Value" ""
			(at 0 0 90)
			(layer "B.Fab")
			(effects
				(font
					(size 1.27 1.27)
				)
				(justify mirror)
			)
		)
		(duplicate_pad_numbers_are_jumpers no)
		(fp_poly
			(pts
				(xy 0.2794 -0.1016) (xy -0.2794 -0.1016) (xy -0.2794 0.9906) (xy 0.2794 0.9906)
			)
			(stroke
				(width 0)
				(type default)
			)
			(fill no)
			(layer "B.CrtYd")
		)
		(fp_line
			(start 0.2794 -0.1016)
			(end 0.2794 0.9906)
			(stroke
				(width 0.1)
				(type default)
			)
			(layer "B.Fab")
		)
		(fp_line
			(start -0.2794 -0.1016)
			(end 0.2794 -0.1016)
			(stroke
				(width 0.1)
				(type default)
			)
			(layer "B.Fab")
		)
		(fp_line
			(start 0.2794 0.9906)
			(end -0.2794 0.9906)
			(stroke
				(width 0.1)
				(type default)
			)
			(layer "B.Fab")
		)
		(fp_line
			(start -0.2794 0.9906)
			(end -0.2794 -0.1016)
			(stroke
				(width 0.1)
				(type default)
			)
			(layer "B.Fab")
		)
		(pad "1" smd rect
			(at 0 0 270)
			(size 0.508 0.508)
			(layers "B.Cu" "B.Mask" "B.Paste")
			(net "VR_PVNN_PCH_XADDR1")
		)
		(pad "2" smd rect
			(at 0 0.889 270)
			(size 0.508 0.508)
			(layers "B.Cu" "B.Mask" "B.Paste")
			(net "GND")
		)
		(zone
			(layer "B.Cu")
			(hatch none 0.5)
			(connect_pads
				(clearance 0)
			)
			(min_thickness 0.25)
			(keepout
				(tracks allowed)
				(vias not_allowed)
				(pads allowed)
				(copperpour not_allowed)
				(footprints allowed)
			)
			(placement
				(enabled no)
				(sheetname "")
			)
			(fill
				(thermal_gap 0.5)
				(thermal_bridge_width 0.5)
				(island_removal_mode 0)
			)
			(polygon
				(pts
					(xy 393.616688 -153.806144) (xy 393.616688 -153.298144) (xy 393.997688 -153.298144) (xy 393.997688 -153.806144)
				)
			)
		)
		(zone
			(layer "B.Cu")
			(hatch none 0.5)
			(connect_pads
				(clearance 0)
			)
			(min_thickness 0.25)
			(keepout
				(tracks not_allowed)
				(vias allowed)
				(pads allowed)
				(copperpour not_allowed)
				(footprints allowed)
			)
			(placement
				(enabled no)
				(sheetname "")
			)
			(fill
				(thermal_gap 0.5)
				(thermal_bridge_width 0.5)
				(island_removal_mode 0)
			)
			(polygon
				(pts
					(xy 393.997688 -153.806144) (xy 393.997688 -153.298144) (xy 393.616688 -153.298144) (xy 393.616688 -153.806144)
				)
			)
		)
	)
	(footprint ""
		(layer "B.Cu")
		(at 101.3968 -12.954 90)
		(property "Reference" "C5G93"
			(at -1.14681 0.76708 180)
			(unlocked yes)
			(layer "B.SilkS")
			(effects
				(font
					(size 0.7874 0.5842)
					(thickness 0.1524)
				)
				(justify mirror)
			)
		)
		(property "Value" ""
			(at 0 0 90)
			(layer "B.Fab")
			(effects
				(font
					(size 1.27 1.27)
				)
				(justify mirror)
			)
		)
		(duplicate_pad_numbers_are_jumpers no)
		(fp_rect
			(start -0.4953 -0.2032)
			(end 0.4953 1.6002)
			(stroke
				(width 0)
				(type default)
			)
			(fill no)
			(layer "B.CrtYd")
		)
		(fp_line
			(start 0.4953 -0.2032)
			(end -0.4953 -0.2032)
			(stroke
				(width 0.1)
				(type default)
			)
			(layer "B.Fab")
		)
		(fp_line
			(start -0.4953 -0.2032)
			(end -0.4953 1.6002)
			(stroke
				(width 0.1)
				(type default)
			)
			(layer "B.Fab")
		)
		(fp_line
			(start 0.4953 1.6002)
			(end 0.4953 -0.2032)
			(stroke
				(width 0.1)
				(type default)
			)
			(layer "B.Fab")
		)
		(fp_line
			(start -0.4953 1.6002)
			(end 0.4953 1.6002)
			(stroke
				(width 0.1)
				(type default)
			)
			(layer "B.Fab")
		)
		(pad "1" smd rect
			(at 0 0 270)
			(size 0.762 0.889)
			(layers "B.Cu" "B.Mask" "B.Paste")
			(net "PVDDQ_GHJ")
		)
		(pad "2" smd rect
			(at 0 1.397 270)
			(size 0.762 0.889)
			(layers "B.Cu" "B.Mask" "B.Paste")
			(net "GND")
		)
		(zone
			(layer "B.Cu")
			(hatch none 0.5)
			(connect_pads
				(clearance 0)
			)
			(min_thickness 0.25)
			(keepout
				(tracks not_allowed)
				(vias allowed)
				(pads allowed)
				(copperpour not_allowed)
				(footprints allowed)
			)
			(placement
				(enabled no)
				(sheetname "")
			)
			(fill
				(thermal_gap 0.5)
				(thermal_bridge_width 0.5)
				(island_removal_mode 0)
			)
			(polygon
				(pts
					(xy 101.8413 -12.573) (xy 102.3493 -12.573) (xy 102.3493 -13.335) (xy 101.8413 -13.335)
				)
			)
		)
	)
	(footprint ""
		(layer "B.Cu")
		(at 390.906 -87.4395)
		(property "Reference" "R2N19"
			(at 0.8382 -0.67818 0)
			(unlocked yes)
			(layer "B.SilkS")
			(effects
				(font
					(size 0.4064 0.254)
					(thickness 0.1524)
				)
				(justify left mirror)
			)
		)
		(property "Value" ""
			(at 0 0 0)
			(layer "B.Fab")
			(effects
				(font
					(size 1.27 1.27)
				)
				(justify mirror)
			)
		)
		(duplicate_pad_numbers_are_jumpers no)
		(fp_poly
			(pts
				(xy 0.2794 -0.1016) (xy -0.2794 -0.1016) (xy -0.2794 0.9906) (xy 0.2794 0.9906)
			)
			(stroke
				(width 0)
				(type default)
			)
			(fill no)
			(layer "B.CrtYd")
		)
		(fp_line
			(start -0.2794 -0.1016)
			(end 0.2794 -0.1016)
			(stroke
				(width 0.1)
				(type default)
			)
			(layer "B.Fab")
		)
		(fp_line
			(start -0.2794 0.9906)
			(end -0.2794 -0.1016)
			(stroke
				(width 0.1)
				(type default)
			)
			(layer "B.Fab")
		)
		(fp_line
			(start 0.2794 -0.1016)
			(end 0.2794 0.9906)
			(stroke
				(width 0.1)
				(type default)
			)
			(layer "B.Fab")
		)
		(fp_line
			(start 0.2794 0.9906)
			(end -0.2794 0.9906)
			(stroke
				(width 0.1)
				(type default)
			)
			(layer "B.Fab")
		)
		(pad "1" smd rect
			(at 0 0 180)
			(size 0.508 0.508)
			(layers "B.Cu" "B.Mask" "B.Paste")
			(net "SGPIO_PCH_SSATA_LOAD")
		)
		(pad "2" smd rect
			(at 0 0.889 180)
			(size 0.508 0.508)
			(layers "B.Cu" "B.Mask" "B.Paste")
			(net "SGPIO_PCH_SSATA_LOAD_R")
		)
		(zone
			(layer "B.Cu")
			(hatch none 0.5)
			(connect_pads
				(clearance 0)
			)
			(min_thickness 0.25)
			(keepout
				(tracks allowed)
				(vias not_allowed)
				(pads allowed)
				(copperpour not_allowed)
				(footprints allowed)
			)
			(placement
				(enabled no)
				(sheetname "")
			)
			(fill
				(thermal_gap 0.5)
				(thermal_bridge_width 0.5)
				(island_removal_mode 0)
			)
			(polygon
				(pts
					(xy 391.16 -87.1855) (xy 390.652 -87.1855) (xy 390.652 -86.8045) (xy 391.16 -86.8045)
				)
			)
		)
		(zone
			(layer "B.Cu")
			(hatch none 0.5)
			(connect_pads
				(clearance 0)
			)
			(min_thickness 0.25)
			(keepout
				(tracks not_allowed)
				(vias allowed)
				(pads allowed)
				(copperpour not_allowed)
				(footprints allowed)
			)
			(placement
				(enabled no)
				(sheetname "")
			)
			(fill
				(thermal_gap 0.5)
				(thermal_bridge_width 0.5)
				(island_removal_mode 0)
			)
			(polygon
				(pts
					(xy 391.16 -86.8045) (xy 390.652 -86.8045) (xy 390.652 -87.1855) (xy 391.16 -87.1855)
				)
			)
		)
	)
	(footprint ""
		(layer "B.Cu")
		(at 410.7307 -8.8138 -90)
		(property "Reference" "R8D42"
			(at 0 0 90)
			(layer "B.SilkS")
			(hide yes)
			(effects
				(font
					(size 1.27 1.27)
				)
				(justify mirror)
			)
		)
		(property "Value" ""
			(at 0 0 90)
			(layer "B.Fab")
			(effects
				(font
					(size 1.27 1.27)
				)
				(justify mirror)
			)
		)
		(duplicate_pad_numbers_are_jumpers no)
		(fp_poly
			(pts
				(xy 0.2794 -0.1016) (xy -0.2794 -0.1016) (xy -0.2794 0.9906) (xy 0.2794 0.9906)
			)
			(stroke
				(width 0)
				(type default)
			)
			(fill no)
			(layer "B.CrtYd")
		)
		(fp_line
			(start -0.2794 0.9906)
			(end -0.2794 -0.1016)
			(stroke
				(width 0.1)
				(type default)
			)
			(layer "B.Fab")
		)
		(fp_line
			(start 0.2794 0.9906)
			(end -0.2794 0.9906)
			(stroke
				(width 0.1)
				(type default)
			)
			(layer "B.Fab")
		)
		(fp_line
			(start -0.2794 -0.1016)
			(end 0.2794 -0.1016)
			(stroke
				(width 0.1)
				(type default)
			)
			(layer "B.Fab")
		)
		(fp_line
			(start 0.2794 -0.1016)
			(end 0.2794 0.9906)
			(stroke
				(width 0.1)
				(type default)
			)
			(layer "B.Fab")
		)
		(pad "1" smd rect
			(at 0 0 90)
			(size 0.508 0.508)
			(layers "B.Cu" "B.Mask" "B.Paste")
			(net "PWRGD_P12V_MAIN_R")
		)
		(pad "2" smd rect
			(at 0 0.889 90)
			(size 0.508 0.508)
			(layers "B.Cu" "B.Mask" "B.Paste")
			(net "PWRGD_P12V_MAIN")
		)
		(zone
			(layer "B.Cu")
			(hatch none 0.5)
			(connect_pads
				(clearance 0)
			)
			(min_thickness 0.25)
			(keepout
				(tracks not_allowed)
				(vias allowed)
				(pads allowed)
				(copperpour not_allowed)
				(footprints allowed)
			)
			(placement
				(enabled no)
				(sheetname "")
			)
			(fill
				(thermal_gap 0.5)
				(thermal_bridge_width 0.5)
				(island_removal_mode 0)
			)
			(polygon
				(pts
					(xy 410.0957 -8.5598) (xy 410.0957 -9.0678) (xy 410.4767 -9.0678) (xy 410.4767 -8.5598)
				)
			)
		)
		(zone
			(layer "B.Cu")
			(hatch none 0.5)
			(connect_pads
				(clearance 0)
			)
			(min_thickness 0.25)
			(keepout
				(tracks allowed)
				(vias not_allowed)
				(pads allowed)
				(copperpour not_allowed)
				(footprints allowed)
			)
			(placement
				(enabled no)
				(sheetname "")
			)
			(fill
				(thermal_gap 0.5)
				(thermal_bridge_width 0.5)
				(island_removal_mode 0)
			)
			(polygon
				(pts
					(xy 410.4767 -8.5598) (xy 410.4767 -9.0678) (xy 410.0957 -9.0678) (xy 410.0957 -8.5598)
				)
			)
		)
	)
)
